G04 ================== begin FILE IDENTIFICATION RECORD ==================*
G04 Layout Name:  12433-1M.brd*
G04 Film Name:    BSMD*
G04 File Format:  Gerber RS274X*
G04 File Origin:  Cadence Allegro 16.2-S037*
G04 Origin Date:  Fri Dec 07 18:55:04 2012*
G04 *
G04 Layer:  VIA CLASS/PASTEMASK_BOTTOM*
G04 Layer:  PIN/PASTEMASK_BOTTOM*
G04 Layer:  PACKAGE GEOMETRY/PASTEMASK_BOTTOM*
G04 Layer:  DRAWING FORMAT/LAYER_PCB_STORY*
G04 Layer:  DRAWING FORMAT/LAYER_PAST_B*
G04 Layer:  BOARD GEOMETRY/PANEL_OUTLINE*
G04 *
G04 Offset:    (0.00 0.00)*
G04 Mirror:    No*
G04 Mode:      Positive*
G04 Rotation:  0*
G04 FullContactRelief:  No*
G04 UndefLineWidth:     6.00*
G04 ================== end FILE IDENTIFICATION RECORD ====================*
%FSLAX35Y35*MOIN*%
%IR0*IPPOS*OFA0.00000B0.00000*MIA0B0*SFA1.00000B1.00000*%
%ADD11R,.05X.05*%
%ADD10C,.14*%
%ADD13C,.02*%
%ADD14C,.006*%
G75*
%LPD*%
G75*
G54D10*
X-222440Y19685D03*
Y1948818D03*
X643700Y19685D03*
Y1948818D03*
G54D11*
X-181139Y20007D03*
X-180444Y1947256D03*
X150000Y64500D03*
X152500Y1906000D03*
X601704Y21248D03*
X602399Y1948497D03*
G36*
G01X96467Y1729085D02*
G03X96447I-10J18750D01*
G01Y1737885D01*
G02X96467I10J9950D01*
G01Y1729085D01*
G37*
G36*
G01Y1804281D02*
G03X96447I-10J18750D01*
G01Y1813081D01*
G02X96467I10J9950D01*
G01Y1804281D01*
G37*
G36*
G01X178947Y1309990D02*
G03X178927I-10J18750D01*
G01Y1318790D01*
G02X178947I10J9950D01*
G01Y1309990D01*
G37*
G36*
G01X161427Y1729085D02*
G03X161407I-10J18750D01*
G01Y1737885D01*
G02X161427I10J9950D01*
G01Y1729085D01*
G37*
G36*
G01Y1804281D02*
G03X161407I-10J18750D01*
G01Y1813081D01*
G02X161427I10J9950D01*
G01Y1804281D01*
G37*
G54D13*
G01X-448201Y-82763D02*
Y-162763D01*
G01Y-118263D02*
X752899D01*
G01X-448201Y-162763D02*
X752899D01*
G01X-452201Y-66763D02*
G02I-12000J0D01*
G01X-457351D02*
G02I-6850J0D01*
G01X-464201Y-82763D02*
Y-50763D01*
G01X-448201Y-66763D02*
X-480201D01*
G01X-448201Y-82763D02*
X752899D01*
G01X-34601D02*
Y-162763D01*
G01X102899Y-82763D02*
Y-162763D01*
G01X217899Y-82763D02*
Y-162763D01*
G01X385399Y-82763D02*
Y-162763D01*
G01X555399Y-82763D02*
Y-162763D01*
G01X752899Y-82763D02*
Y-162763D01*
G01X780899Y-66763D02*
G02I-12000J0D01*
G01X775749D02*
G02I-6850J0D01*
G01X768899Y-82763D02*
Y-50763D01*
G01X784899Y-66763D02*
X752899D01*
G54D14*
G01X-430254Y-152763D02*
Y-135263D01*
G01X-421958D02*
X-430254Y-146055D01*
G01X-420648Y-152763D02*
X-426543Y-141097D01*
G01X-412973Y-152763D02*
Y-135263D01*
X-402929Y-152763D01*
Y-135263D01*
G01X-390451Y-152763D02*
X-392198Y-152471D01*
X-393726Y-151305D01*
X-395036Y-149555D01*
X-395910Y-147513D01*
X-396346Y-145180D01*
Y-142846D01*
X-395910Y-140513D01*
X-395036Y-138471D01*
X-393726Y-136722D01*
X-392198Y-135555D01*
X-390451Y-135263D01*
X-388705Y-135555D01*
X-387176Y-136722D01*
X-385866Y-138471D01*
X-384992Y-140513D01*
X-384556Y-142846D01*
Y-145180D01*
X-384992Y-147513D01*
X-385866Y-149555D01*
X-387176Y-151305D01*
X-388705Y-152471D01*
X-390451Y-152763D01*
G01X-377536D02*
X-368366Y-135263D01*
G01X-377536D02*
X-368366Y-152763D01*
G01X-362001Y-158596D02*
X-348901D01*
G01X-342099Y-152763D02*
Y-135263D01*
X-333803D01*
G01X-336859Y-143721D02*
X-342099D01*
G01X-325910Y-152763D02*
X-320451Y-135263D01*
X-314992Y-152763D01*
G01X-316958Y-146638D02*
X-323945D01*
G01X-307973Y-152763D02*
Y-135263D01*
X-297929Y-152763D01*
Y-135263D01*
G01X-263148Y-136722D02*
X-264458Y-135846D01*
X-265986Y-135263D01*
X-267733D01*
X-269698Y-136138D01*
X-271226Y-137596D01*
X-272318Y-139347D01*
X-273191Y-142263D01*
X-273410Y-144888D01*
X-272973Y-147513D01*
X-272318Y-149263D01*
X-271008Y-151013D01*
X-269479Y-152180D01*
X-267951Y-152763D01*
X-266423D01*
X-264894Y-152180D01*
X-263584Y-151305D01*
X-262492Y-150139D01*
G01X-250451Y-152763D02*
X-252198Y-152471D01*
X-253726Y-151305D01*
X-255036Y-149555D01*
X-255910Y-147513D01*
X-256346Y-145180D01*
Y-142846D01*
X-255910Y-140513D01*
X-255036Y-138471D01*
X-253726Y-136722D01*
X-252198Y-135555D01*
X-250451Y-135263D01*
X-248705Y-135555D01*
X-247176Y-136722D01*
X-245866Y-138471D01*
X-244992Y-140513D01*
X-244556Y-142846D01*
Y-145180D01*
X-244992Y-147513D01*
X-245866Y-149555D01*
X-247176Y-151305D01*
X-248705Y-152471D01*
X-250451Y-152763D01*
G01X-237973D02*
Y-135263D01*
X-227929Y-152763D01*
Y-135263D01*
G01X-215451D02*
Y-152763D01*
G01X-220473Y-135263D02*
X-210429D01*
G01X-202318Y-152763D02*
Y-135263D01*
X-196859D01*
X-195113Y-136138D01*
X-194021Y-137305D01*
X-193584Y-139638D01*
X-194021Y-141972D01*
X-195331Y-143430D01*
X-196859Y-144305D01*
X-202318D01*
G01X-196859D02*
X-193584Y-152763D01*
G01X-180451D02*
X-182198Y-152471D01*
X-183726Y-151305D01*
X-185036Y-149555D01*
X-185910Y-147513D01*
X-186346Y-145180D01*
Y-142846D01*
X-185910Y-140513D01*
X-185036Y-138471D01*
X-183726Y-136722D01*
X-182198Y-135555D01*
X-180451Y-135263D01*
X-178705Y-135555D01*
X-177176Y-136722D01*
X-175866Y-138471D01*
X-174992Y-140513D01*
X-174556Y-142846D01*
Y-145180D01*
X-174992Y-147513D01*
X-175866Y-149555D01*
X-177176Y-151305D01*
X-178705Y-152471D01*
X-180451Y-152763D01*
G01X-167318Y-135263D02*
Y-152763D01*
X-158584D01*
G01X-126205Y-143430D02*
X-125331Y-142555D01*
X-124676Y-141097D01*
X-124239Y-139054D01*
X-124676Y-137305D01*
X-125549Y-136138D01*
X-127078Y-135263D01*
X-132973D01*
Y-152763D01*
X-125768D01*
X-124239Y-151597D01*
X-123366Y-149846D01*
X-122929Y-147805D01*
X-123366Y-145763D01*
X-124676Y-144013D01*
X-126205Y-143430D01*
X-132973D01*
G01X-110451Y-152763D02*
X-112198Y-152471D01*
X-113726Y-151305D01*
X-115036Y-149555D01*
X-115910Y-147513D01*
X-116346Y-145180D01*
Y-142846D01*
X-115910Y-140513D01*
X-115036Y-138471D01*
X-113726Y-136722D01*
X-112198Y-135555D01*
X-110451Y-135263D01*
X-108705Y-135555D01*
X-107176Y-136722D01*
X-105866Y-138471D01*
X-104992Y-140513D01*
X-104556Y-142846D01*
Y-145180D01*
X-104992Y-147513D01*
X-105866Y-149555D01*
X-107176Y-151305D01*
X-108705Y-152471D01*
X-110451Y-152763D01*
G01X-98410D02*
X-92951Y-135263D01*
X-87492Y-152763D01*
G01X-89458Y-146638D02*
X-96445D01*
G01X-79818Y-152763D02*
Y-135263D01*
X-74359D01*
X-72613Y-136138D01*
X-71521Y-137305D01*
X-71084Y-139638D01*
X-71521Y-141972D01*
X-72831Y-143430D01*
X-74359Y-144305D01*
X-79818D01*
G01X-74359D02*
X-71084Y-152763D01*
G01X-62754D02*
Y-135263D01*
X-58388D01*
X-56641Y-136138D01*
X-55331Y-137305D01*
X-54239Y-139054D01*
X-53366Y-141097D01*
X-53148Y-144013D01*
X-53366Y-146930D01*
X-54239Y-148972D01*
X-55331Y-150722D01*
X-56641Y-151888D01*
X-58388Y-152763D01*
X-62754D01*
G01X-282378Y-107763D02*
Y-90263D01*
X-276701Y-104846D01*
X-271024Y-90263D01*
Y-107763D01*
G01X-259201D02*
X-260511Y-107471D01*
X-261821Y-106305D01*
X-262695Y-104263D01*
X-263131Y-101930D01*
X-262695Y-99596D01*
X-261821Y-97555D01*
X-260511Y-96388D01*
X-259201Y-96097D01*
X-257891Y-96388D01*
X-256581Y-97555D01*
X-255708Y-99596D01*
X-255489Y-101930D01*
X-255708Y-104263D01*
X-256581Y-106305D01*
X-257891Y-107471D01*
X-259201Y-107763D01*
G01X-237771Y-90263D02*
Y-107763D01*
G01Y-105139D02*
X-238644Y-106597D01*
X-239955Y-107471D01*
X-241483Y-107763D01*
X-243229Y-107180D01*
X-244539Y-105722D01*
X-245413Y-103972D01*
X-245631Y-101930D01*
X-245413Y-99888D01*
X-244539Y-98138D01*
X-243229Y-96680D01*
X-241483Y-96097D01*
X-239955Y-96388D01*
X-238863Y-96972D01*
X-237771Y-98138D01*
G01X-227476Y-99888D02*
X-220489D01*
X-221144Y-97846D01*
X-222236Y-96680D01*
X-223764Y-96097D01*
X-225293Y-96388D01*
X-226603Y-97263D01*
X-227476Y-99305D01*
X-227913Y-101055D01*
Y-102805D01*
X-227476Y-104555D01*
X-226384Y-106305D01*
X-225074Y-107471D01*
X-223546Y-107763D01*
X-222018Y-107180D01*
X-220489Y-105430D01*
G01X-206701Y-107763D02*
Y-90263D01*
G01X-242126Y15000D02*
G03X-227126Y0I15000J0D01*
G01X-242126Y1953504D02*
Y15000D01*
G01X-215453Y19685D02*
G03I-6988J0D01*
G01X-84646Y0D02*
X-227126D01*
G01X-215453Y19685D02*
G03I-6988J0D01*
G01D02*
G03I-6988J0D01*
G01X-227126Y1968504D02*
G03X-242126Y1953504I0J-15000D01*
G01X-215453Y1948819D02*
G03I-6988J0D01*
G01X-84638Y1968504D02*
X-227126D01*
G01X-215453Y1948819D02*
G03I-6988J0D01*
G01D02*
G03I-6988J0D01*
G01X-222441Y39370D02*
G03X-214567Y31496I7874J0D01*
G01X-206693D02*
X-214567D01*
G01X-175984D02*
X-84646D01*
G01X-206693D02*
G03Y39370I0J3937D01*
G01X-175984D02*
G03Y31496I0J-3937D01*
G01X-206693D02*
X-214567D01*
G01X-84646Y0D02*
X-199567D01*
G01X-175984Y31496D02*
X-84646D01*
G01X-206693D02*
G03Y39370I0J3937D01*
G01X-175984D02*
G03Y31496I0J-3937D01*
G01X-222441Y169326D02*
Y39370D01*
G01X-214567Y43307D02*
G03X-210630Y39370I3937J0D01*
G01X-214567Y43307D02*
G03X-210630Y39370I3937J0D01*
G01X-80709D02*
X-210630D01*
G01X-80709D02*
X-210630D01*
G01X-214567Y43307D02*
Y1925197D01*
G01Y43307D02*
Y1925197D01*
G01Y149606D02*
Y43307D01*
G01Y149606D02*
Y43272D01*
G01Y169326D02*
G03X-222441I-3937J0D01*
G01X-214567D02*
G03X-222441I-3937J0D01*
G01X-214567Y1807087D02*
Y161417D01*
G01Y1807087D02*
Y161417D01*
G01X-222441Y436255D02*
Y200034D01*
G01D02*
G03X-214567I3937J0D01*
G01X-222441D02*
G03X-214567I3937J0D01*
G01Y436255D02*
G03X-222441I-3937J0D01*
G01X-214567D02*
G03X-222441I-3937J0D01*
G01Y703184D02*
Y466963D01*
G01D02*
G03X-214567I3937J0D01*
G01X-222441D02*
G03X-214567I3937J0D01*
G01X-222441Y970901D02*
Y733892D01*
G01X-214567Y703184D02*
G03X-222441I-3937J0D01*
G01Y733892D02*
G03X-214567I3937J0D01*
G01Y703184D02*
G03X-222441I-3937J0D01*
G01Y733892D02*
G03X-214567I3937J0D01*
G01X-222441Y1234681D02*
Y997672D01*
G01X-214567Y970901D02*
G03X-222441I-3937J0D01*
G01Y997672D02*
G03X-214567I3937J0D01*
G01Y970901D02*
G03X-222441I-3937J0D01*
G01Y997672D02*
G03X-214567I3937J0D01*
G01X-222441Y1265389D02*
G03X-214567I3937J0D01*
G01Y1234681D02*
G03X-222441I-3937J0D01*
G01Y1265389D02*
G03X-214567I3937J0D01*
G01Y1234681D02*
G03X-222441I-3937J0D01*
G01Y1501610D02*
Y1265389D01*
G01X-214567Y1501610D02*
G03X-222441I-3937J0D01*
G01X-214567D02*
G03X-222441I-3937J0D01*
G01Y1768539D02*
Y1532318D01*
G01D02*
G03X-214567I3937J0D01*
G01X-222441D02*
G03X-214567I3937J0D01*
G01Y1768539D02*
G03X-222441I-3937J0D01*
G01X-214567D02*
G03X-222441I-3937J0D01*
G01Y1799247D02*
G03X-214567I3937J0D01*
G01X-222441D02*
G03X-214567I3937J0D01*
G01X-222441Y1929134D02*
Y1799247D01*
G01X-214567Y1818898D02*
Y1925231D01*
G01Y1818898D02*
Y1925231D01*
G01X-210630Y1929134D02*
G03X-214567Y1925197I0J-3937D01*
G01X-210630Y1929134D02*
G03X-214567Y1925197I0J-3937D01*
G01Y1937008D02*
G03X-222441Y1929134I0J-7874D01*
G01X-210630D02*
X-80709D01*
G01X-210630D02*
X-80709D01*
G01X-175984Y1937008D02*
X-84638D01*
G01X-214567D02*
X-206693D01*
G01X-175984D02*
G03Y1929134I0J-3937D01*
G01X-206693D02*
G03Y1937008I0J3937D01*
G01X-84638Y1968504D02*
X-199567D01*
G01X-175984Y1937008D02*
X-84638D01*
G01X-214567D02*
X-206693D01*
G01X-175984D02*
G03Y1929134I0J-3937D01*
G01X-206693D02*
G03Y1937008I0J3937D01*
G01X-76772Y3937D02*
G03X-72835Y0I3937J0D01*
G01X-76772Y35433D02*
G03X-80709Y39370I-3937J0D01*
G01X-76772Y35433D02*
G03X-80709Y39370I-3937J0D01*
G01X-76772Y3937D02*
G03X-72835Y0I3937J0D01*
G01X-76772Y3937D02*
Y35433D01*
G01Y3937D02*
Y35433D01*
G01Y3937D02*
G03X-72835Y0I3937J0D01*
G01X-84646Y7874D02*
Y0D01*
G01X-76772Y7874D02*
G03X-84646I-3937J0D01*
G01Y31496D02*
G03X-76772I3937J0D01*
G01Y3937D02*
G03X-72835Y0I3937J0D01*
G01X-84646Y7874D02*
Y0D01*
G01X-76772Y7874D02*
G03X-84646I-3937J0D01*
G01Y31496D02*
G03X-76772I3937J0D01*
G01X-76763Y1937008D02*
G03X-84638I-3937J0D01*
G01X-80709Y1929134D02*
G03X-76772Y1933071I0J3937D01*
G01X-80709Y1929134D02*
G03X-76772Y1933071I0J3937D01*
G01X-72835Y1968504D02*
G03X-76772Y1964567I0J-3937D01*
G01X-72835Y1968504D02*
G03X-76772Y1964567I0J-3937D01*
G01Y1933071D02*
Y1964567D01*
G01Y1933071D02*
Y1964567D01*
G01X-72835Y1968504D02*
G03X-76772Y1964567I0J-3937D01*
G01X-84638Y1960889D02*
Y1968504D01*
G01Y1960889D02*
G03X-76763I3938J0D01*
G01X-72835Y1968504D02*
G03X-76772Y1964567I0J-3937D01*
G01X-84638Y1960889D02*
Y1968504D01*
G01Y1960889D02*
G03X-76763I3938J0D01*
G01X-11811Y0D02*
X-72835D01*
G01X-11811D02*
X-72835D01*
G01D02*
X-11811D01*
G01X-72835D02*
X-11811D01*
G01X-72835Y1968504D02*
X-11811D01*
G01X-72835D02*
X-11811D01*
G01D02*
X-72835D01*
G01X-11811D02*
X-72835D01*
G01X-901Y-152763D02*
Y-135263D01*
X-3521Y-138763D01*
G01Y-152763D02*
X1719D01*
G01X12451Y-138180D02*
X13761Y-136430D01*
X15289Y-135555D01*
X17036Y-135263D01*
X19219Y-135846D01*
X20747Y-137305D01*
X21184Y-139054D01*
X20966Y-140805D01*
X20092Y-142263D01*
X15726Y-145180D01*
X13761Y-147221D01*
X12451Y-150139D01*
X12014Y-152763D01*
X21184D01*
G01X36719D02*
Y-135263D01*
X28640Y-147805D01*
X39558D01*
G01X46796Y-149263D02*
X48105Y-151305D01*
X49852Y-152471D01*
X51817Y-152763D01*
X53564Y-152471D01*
X55311Y-151013D01*
X56402Y-149263D01*
X56621Y-147513D01*
X56184Y-145472D01*
X54656Y-144013D01*
X53127Y-143430D01*
X51162D01*
G01X53127D02*
X54437Y-142555D01*
X55529Y-141097D01*
X55966Y-139347D01*
X55529Y-137596D01*
X54437Y-136138D01*
X52472Y-135263D01*
X50507Y-135555D01*
X48542Y-136722D01*
G01X64296Y-149263D02*
X65605Y-151305D01*
X67352Y-152471D01*
X69317Y-152763D01*
X71064Y-152471D01*
X72811Y-151013D01*
X73902Y-149263D01*
X74121Y-147513D01*
X73684Y-145472D01*
X72156Y-144013D01*
X70627Y-143430D01*
X68662D01*
G01X70627D02*
X71937Y-142555D01*
X73029Y-141097D01*
X73466Y-139347D01*
X73029Y-137596D01*
X71937Y-136138D01*
X69972Y-135263D01*
X68007Y-135555D01*
X66042Y-136722D01*
G01X-14018Y-107763D02*
Y-90263D01*
X-8778D01*
X-7031Y-91138D01*
X-5721Y-93180D01*
X-5284Y-95513D01*
X-5721Y-97846D01*
X-6813Y-99596D01*
X-8778Y-100472D01*
X-14018D01*
G01X12652Y-91722D02*
X11342Y-90846D01*
X9814Y-90263D01*
X8067D01*
X6102Y-91138D01*
X4574Y-92596D01*
X3482Y-94347D01*
X2609Y-97263D01*
X2390Y-99888D01*
X2827Y-102513D01*
X3482Y-104263D01*
X4792Y-106013D01*
X6321Y-107180D01*
X7849Y-107763D01*
X9377D01*
X10906Y-107180D01*
X12216Y-106305D01*
X13308Y-105139D01*
G01X27095Y-98430D02*
X27969Y-97555D01*
X28624Y-96097D01*
X29061Y-94054D01*
X28624Y-92305D01*
X27751Y-91138D01*
X26222Y-90263D01*
X20327D01*
Y-107763D01*
X27532D01*
X29061Y-106597D01*
X29934Y-104846D01*
X30371Y-102805D01*
X29934Y-100763D01*
X28624Y-99013D01*
X27095Y-98430D01*
X20327D01*
G01X36299Y-113596D02*
X49399D01*
G01X55327Y-107763D02*
Y-90263D01*
X65371Y-107763D01*
Y-90263D01*
G01X77849Y-107763D02*
X76102Y-107471D01*
X74574Y-106305D01*
X73264Y-104555D01*
X72390Y-102513D01*
X71954Y-100180D01*
Y-97846D01*
X72390Y-95513D01*
X73264Y-93471D01*
X74574Y-91722D01*
X76102Y-90555D01*
X77849Y-90263D01*
X79595Y-90555D01*
X81124Y-91722D01*
X82434Y-93471D01*
X83308Y-95513D01*
X83744Y-97846D01*
Y-100180D01*
X83308Y-102513D01*
X82434Y-104555D01*
X81124Y-106305D01*
X79595Y-107471D01*
X77849Y-107763D01*
G01X-11811Y0D02*
G03X-7874Y3937I0J3937D01*
G01X-11811Y0D02*
G03X-7874Y3937I0J3937D01*
G01Y43110D02*
Y3937D01*
G01Y43110D02*
Y3937D01*
G01X0D02*
G03X3937Y0I3937J0D01*
G01X0Y3937D02*
G03X3937Y0I3937J0D01*
G01X0Y3937D02*
Y43110D01*
G01Y3937D02*
Y43110D01*
G01X64961Y0D02*
X3937D01*
G01X64961D02*
X3937D01*
G01X0Y3937D02*
G03X3937Y0I3937J0D01*
G01X0Y1964567D02*
Y3937D01*
G01X3937Y0D02*
X64961D01*
G01X-7874Y3937D02*
Y1964567D01*
G01X-11811Y0D02*
G03X-7874Y3937I0J3937D01*
G01X0Y11811D02*
G03X-7874I-3937J0D01*
G01X0Y3937D02*
G03X3937Y0I3937J0D01*
G01X0Y1964567D02*
Y3937D01*
G01X3937Y0D02*
X64961D01*
G01X-7874Y3937D02*
Y1964567D01*
G01X-11811Y0D02*
G03X-7874Y3937I0J3937D01*
G01X0Y11811D02*
G03X-7874I-3937J0D01*
G01Y93110D02*
Y43110D01*
G01Y93110D02*
Y43110D01*
G01X0D02*
Y93110D01*
G01Y43110D02*
Y93110D01*
G01X-7874Y42520D02*
G03X0I3937J0D01*
G01X-7874D02*
G03X0I3937J0D01*
G01X-7874Y214764D02*
Y93110D01*
G01Y214764D02*
Y93110D01*
G01X0D02*
Y214764D01*
G01Y93110D02*
Y214764D01*
G01X-7874Y226968D02*
Y214764D01*
G01Y226968D02*
Y214764D01*
G01Y342461D02*
Y226968D01*
G01Y342461D02*
Y226968D01*
G01X0Y226969D02*
Y342461D01*
G01Y226969D02*
Y342461D01*
G01Y214764D02*
Y226969D01*
G01Y214764D02*
Y226969D01*
G01Y278740D02*
G03X-7874I-3937J0D01*
G01X0D02*
G03X-7874I-3937J0D01*
G01Y354665D02*
Y342461D01*
G01Y354665D02*
Y342461D01*
G01X0D02*
Y354665D01*
G01Y342461D02*
Y354665D01*
G01X-7874Y309449D02*
G03X0I3937J0D01*
G01X-7874D02*
G03X0I3937J0D01*
G01X-7874Y476339D02*
Y354665D01*
G01Y476339D02*
Y354665D01*
G01X0D02*
Y476339D01*
G01Y354665D02*
Y476339D01*
G01X-7874Y526339D02*
Y476339D01*
G01Y526339D02*
Y476339D01*
G01X0D02*
Y526339D01*
G01Y476339D02*
Y526339D01*
G01X-7874Y736181D02*
Y526339D01*
G01Y736181D02*
Y526339D01*
G01X0D02*
Y736181D01*
G01Y526339D02*
Y736181D01*
G01Y545669D02*
G03X-7874I-3937J0D01*
G01X0D02*
G03X-7874I-3937J0D01*
G01Y576378D02*
G03X0I3937J0D01*
G01X-7874D02*
G03X0I3937J0D01*
G01X-7874Y786181D02*
Y736181D01*
G01Y786181D02*
Y736181D01*
G01X0D02*
Y786181D01*
G01Y736181D02*
Y786181D01*
G01X-7874Y907815D02*
Y786181D01*
G01Y907815D02*
Y786181D01*
G01X0D02*
Y907815D01*
G01Y786181D02*
Y907815D01*
G01Y831496D02*
G03X-7874I-3937J0D01*
G01X0D02*
G03X-7874I-3937J0D01*
G01Y862205D02*
G03X0I3937J0D01*
G01X-7874D02*
G03X0I3937J0D01*
G01X-7874Y920020D02*
Y907815D01*
G01Y920020D02*
Y907815D01*
G01Y1048484D02*
Y920020D01*
G01Y1048484D02*
Y920020D01*
G01X0D02*
Y1048484D01*
G01Y920020D02*
Y1048484D01*
G01Y907815D02*
Y920020D01*
G01Y907815D02*
Y920020D01*
G01X-7874Y1060689D02*
Y1048484D01*
G01Y1060689D02*
Y1048484D01*
G01X0D02*
Y1060689D01*
G01Y1048484D02*
Y1060689D01*
G01X-7874Y1182323D02*
Y1060689D01*
G01Y1182323D02*
Y1060689D01*
G01X0D02*
Y1182323D01*
G01Y1060689D02*
Y1182323D01*
G01Y1106299D02*
G03X-7874I-3937J0D01*
G01X0D02*
G03X-7874I-3937J0D01*
G01Y1137008D02*
G03X0I3937J0D01*
G01X-7874D02*
G03X0I3937J0D01*
G01X-7874Y1232323D02*
Y1182323D01*
G01Y1232323D02*
Y1182323D01*
G01X0D02*
Y1232323D01*
G01Y1182323D02*
Y1232323D01*
G01X-7874Y1442165D02*
Y1232323D01*
G01Y1442165D02*
Y1232323D01*
G01X0D02*
Y1442165D01*
G01Y1232323D02*
Y1442165D01*
G01Y1392126D02*
G03X-7874I-3937J0D01*
G01X0D02*
G03X-7874I-3937J0D01*
G01Y1492165D02*
Y1442165D01*
G01Y1492165D02*
Y1442165D01*
G01X0D02*
Y1492165D01*
G01Y1442165D02*
Y1492165D01*
G01X-7874Y1422835D02*
G03X0I3937J0D01*
G01X-7874D02*
G03X0I3937J0D01*
G01X-7874Y1613839D02*
Y1492165D01*
G01Y1613839D02*
Y1492165D01*
G01X0D02*
Y1613839D01*
G01Y1492165D02*
Y1613839D01*
G01X-7874Y1626043D02*
Y1613839D01*
G01Y1626043D02*
Y1613839D01*
G01X0D02*
Y1626043D01*
G01Y1613839D02*
Y1626043D01*
G01X-7874Y1741535D02*
Y1626043D01*
G01Y1741535D02*
Y1626043D01*
G01X0D02*
Y1741535D01*
G01Y1626043D02*
Y1741535D01*
G01Y1659055D02*
G03X-7874I-3937J0D01*
G01X0D02*
G03X-7874I-3937J0D01*
G01Y1689764D02*
G03X0I3937J0D01*
G01X-7874D02*
G03X0I3937J0D01*
G01X-7874Y1753740D02*
Y1741535D01*
G01Y1753740D02*
Y1741535D01*
G01Y1875394D02*
Y1753740D01*
G01Y1875394D02*
Y1753740D01*
G01X0D02*
Y1875394D01*
G01Y1753740D02*
Y1875394D01*
G01Y1741535D02*
Y1753740D01*
G01Y1741535D02*
Y1753740D01*
G01X-7874Y1925394D02*
Y1875394D01*
G01Y1925394D02*
Y1875394D01*
G01X0D02*
Y1925394D01*
G01Y1875394D02*
Y1925394D01*
G01X-7874Y1964567D02*
Y1925394D01*
G01Y1964567D02*
Y1925394D01*
G01X0D02*
Y1964567D01*
G01Y1925394D02*
Y1964567D01*
G01Y1925984D02*
G03X-7874I-3937J0D01*
G01X0D02*
G03X-7874I-3937J0D01*
G01Y1964567D02*
G03X-11811Y1968504I-3937J0D01*
G01X-7874Y1964567D02*
G03X-11811Y1968504I-3937J0D01*
G01X3937D02*
G03X0Y1964567I0J-3937D01*
G01X3937Y1968504D02*
G03X0Y1964567I0J-3937D01*
G01X3937Y1968504D02*
X64961D01*
G01X3937D02*
X64961D01*
G01X3937D02*
G03X0Y1964567I0J-3937D01*
G01X64961Y1968504D02*
X3937D01*
G01X-7874Y1964567D02*
G03X-11811Y1968504I-3937J0D01*
G01X-7874Y1956693D02*
G03X0I3937J0D01*
G01X3937Y1968504D02*
G03X0Y1964567I0J-3937D01*
G01X64961Y1968504D02*
X3937D01*
G01X-7874Y1964567D02*
G03X-11811Y1968504I-3937J0D01*
G01X-7874Y1956693D02*
G03X0I3937J0D01*
G01X168110Y31496D02*
X76763D01*
G01X72835Y39370D02*
G03X68898Y35433I0J-3937D01*
G01X72835Y39370D02*
G03X68898Y35433I0J-3937D01*
G01X64961Y0D02*
G03X68898Y3937I0J3937D01*
G01X64961Y0D02*
G03X68898Y3937I0J3937D01*
G01Y35433D02*
Y3937D01*
G01Y35433D02*
Y3937D01*
G01X72835Y39370D02*
G03X68898Y35433I0J-3937D01*
G01Y3937D02*
Y35485D01*
G01X64961Y0D02*
G03X68898Y3937I0J3937D01*
G01X76763D02*
G03X80700Y0I3937J0D01*
G01X76763Y7615D02*
Y3937D01*
G01X168110Y31496D02*
X76763D01*
G01Y7615D02*
G03X68889I-3937J0D01*
G01Y31496D02*
G03X76763I3937J0D01*
G01X72835Y39370D02*
G03X68898Y35433I0J-3937D01*
G01Y3937D02*
Y35485D01*
G01X64961Y0D02*
G03X68898Y3937I0J3937D01*
G01X76763D02*
G03X80700Y0I3937J0D01*
G01X76763Y7615D02*
Y3937D01*
G01X168110Y31496D02*
X76763D01*
G01Y7615D02*
G03X68889I-3937J0D01*
G01Y31496D02*
G03X76763I3937J0D01*
G01X202756Y39370D02*
X72835D01*
G01X202756D02*
X72835D01*
G01D02*
X202756D01*
G01X72835D02*
X202756D01*
G01X68898Y1964567D02*
G03X64961Y1968504I-3937J0D01*
G01X68898Y1933071D02*
G03X72835Y1929134I3937J0D01*
G01X68898Y1933071D02*
G03X72835Y1929134I3937J0D01*
G01X68898Y1964567D02*
G03X64961Y1968504I-3937J0D01*
G01X72835Y1929134D02*
X202756D01*
G01X72835D02*
X202756D01*
G01X68898Y1964567D02*
Y1933071D01*
G01Y1964567D02*
Y1933071D01*
G01Y1964567D02*
G03X64961Y1968504I-3937J0D01*
G01X68898Y1933071D02*
Y1964567D01*
G01Y1933071D02*
G03X72835Y1929134I3937J0D01*
G01X202756D02*
X72835D01*
G01X80709Y1968504D02*
G03X76772Y1964567I0J-3937D01*
G01Y1960630D02*
Y1964567D01*
G01X168110Y1937008D02*
X76772D01*
G01X68898Y1960630D02*
G03X76772I3937J0D01*
G01Y1937008D02*
G03X68898I-3937J0D01*
G01Y1964567D02*
G03X64961Y1968504I-3937J0D01*
G01X68898Y1933071D02*
Y1964567D01*
G01Y1933071D02*
G03X72835Y1929134I3937J0D01*
G01X202756D02*
X72835D01*
G01X80709Y1968504D02*
G03X76772Y1964567I0J-3937D01*
G01Y1960630D02*
Y1964567D01*
G01X168110Y1937008D02*
X76772D01*
G01X68898Y1960630D02*
G03X76772I3937J0D01*
G01Y1937008D02*
G03X68898I-3937J0D01*
G01X128690Y-90263D02*
X134149Y-107763D01*
X139608Y-90263D01*
G01X156016Y-107763D02*
X147282D01*
Y-90263D01*
X156016D01*
G01X152522Y-98721D02*
X147282D01*
G01X164782Y-107763D02*
Y-90263D01*
X170241D01*
X171987Y-91138D01*
X173079Y-92305D01*
X173516Y-94638D01*
X173079Y-96972D01*
X171769Y-98430D01*
X170241Y-99305D01*
X164782D01*
G01X170241D02*
X173516Y-107763D01*
G01X186649Y-108346D02*
X186212Y-108055D01*
Y-107471D01*
X186649Y-107180D01*
X187086Y-107471D01*
Y-108055D01*
X186649Y-108346D01*
G01X80700Y0D02*
X340551D01*
G01X80700D02*
X340551D01*
G01X118011Y1968504D02*
X142520D01*
G01X109377D02*
X110137D01*
G01X109377D02*
X80709D01*
G01X110137D02*
G03X118011I3937J0D01*
G01X109377D02*
X80709D01*
G01X110137D02*
G03X118011I3937J0D01*
G01X151649Y-152763D02*
Y-135263D01*
X149029Y-138763D01*
G01Y-152763D02*
X154269D01*
G01X163472D02*
Y-135263D01*
X169149Y-149846D01*
X174826Y-135263D01*
Y-152763D01*
G01X168110Y31496D02*
G03Y39370I0J3937D01*
G01Y31496D02*
G03Y39370I0J3937D01*
G01X340559Y1968504D02*
X142520D01*
G01X168110Y1929134D02*
G03Y1937008I0J3937D01*
G01X340559Y1968504D02*
X142520D01*
G01X168110Y1929134D02*
G03Y1937008I0J3937D01*
G01X222441Y31496D02*
X198819D01*
G01X222441D02*
G03Y39370I0J3937D01*
G01X198819D02*
G03Y31496I0J-3937D01*
G01X222441D02*
X198819D01*
G01X222441D02*
G03Y39370I0J3937D01*
G01X198819D02*
G03Y31496I0J-3937D01*
G01X214567Y161417D02*
Y43307D01*
G01X202756Y39370D02*
G03X206693Y43307I0J3937D01*
G01X202756Y39370D02*
G03X206693Y43307I0J3937D01*
G01Y1925197D02*
Y43307D01*
G01Y1925197D02*
Y43307D01*
G01X202756Y39370D02*
G03X206693Y43307I0J3937D01*
G01X218504Y39370D02*
X348425D01*
G01X214567Y43307D02*
G03X218504Y39370I3937J0D01*
G01X202756D02*
G03X206693Y43307I0J3937D01*
G01X218504Y39370D02*
X348425D01*
G01X214567Y43307D02*
G03X218504Y39370I3937J0D01*
G01X206693Y161417D02*
Y1807087D01*
G01X214567D02*
Y161417D01*
G01Y169291D02*
G03X206693I-3937J0D01*
G01Y161417D02*
Y1807087D01*
G01X214567D02*
Y161417D01*
G01Y169291D02*
G03X206693I-3937J0D01*
G01Y200000D02*
G03X214567I3937J0D01*
G01X206693D02*
G03X214567I3937J0D01*
G01Y436220D02*
G03X206693I-3937J0D01*
G01X214567D02*
G03X206693I-3937J0D01*
G01Y466929D02*
G03X214567I3937J0D01*
G01X206693D02*
G03X214567I3937J0D01*
G01Y703149D02*
G03X206693I-3937J0D01*
G01Y733858D02*
G03X214567I3937J0D01*
G01Y703149D02*
G03X206693I-3937J0D01*
G01Y733858D02*
G03X214567I3937J0D01*
G01Y970867D02*
G03X206693I-3937J0D01*
G01Y997637D02*
G03X214567I3937J0D01*
G01Y970867D02*
G03X206693I-3937J0D01*
G01Y997637D02*
G03X214567I3937J0D01*
G01X206693Y1265355D02*
G03X214567I3937J0D01*
G01Y1234646D02*
G03X206693I-3937J0D01*
G01Y1265355D02*
G03X214567I3937J0D01*
G01Y1234646D02*
G03X206693I-3937J0D01*
G01X214567Y1501575D02*
G03X206693I-3937J0D01*
G01X214567D02*
G03X206693I-3937J0D01*
G01Y1532284D02*
G03X214567I3937J0D01*
G01X206693D02*
G03X214567I3937J0D01*
G01Y1768504D02*
G03X206693I-3937J0D01*
G01X214567D02*
G03X206693I-3937J0D01*
G01X214567Y1807087D02*
Y1925197D01*
G01X206693Y1799213D02*
G03X214567I3937J0D01*
G01X206693D02*
G03X214567I3937J0D01*
G01X206693Y1925197D02*
G03X202756Y1929134I-3937J0D01*
G01X206693Y1925197D02*
G03X202756Y1929134I-3937J0D01*
G01X206693Y1925197D02*
G03X202756Y1929134I-3937J0D01*
G01X218504D02*
G03X214567Y1925197I0J-3937D01*
G01X206693D02*
G03X202756Y1929134I-3937J0D01*
G01X218504D02*
G03X214567Y1925197I0J-3937D01*
G01X348425Y1929134D02*
X218504D01*
G01X198819Y1937008D02*
X222441D01*
G01X198819D02*
G03Y1929134I0J-3937D01*
G01X222441D02*
G03Y1937008I0J3937D01*
G01X348425Y1929134D02*
X218504D01*
G01X198819Y1937008D02*
X222441D01*
G01X198819D02*
G03Y1929134I0J-3937D01*
G01X222441D02*
G03Y1937008I0J3937D01*
G01X326103Y-143430D02*
X325229Y-142555D01*
X324574Y-141097D01*
X324137Y-139054D01*
X324574Y-137305D01*
X325447Y-136138D01*
X326976Y-135263D01*
X332871D01*
Y-152763D01*
X325666D01*
X324137Y-151597D01*
X323264Y-149846D01*
X322827Y-147805D01*
X323264Y-145763D01*
X324574Y-144013D01*
X326103Y-143430D01*
X332871D01*
G01X314934Y-150430D02*
X313187Y-151888D01*
X311222Y-152763D01*
X309476D01*
X307729Y-151888D01*
X306419Y-150430D01*
X305764Y-148388D01*
X306201Y-146347D01*
X307292Y-144596D01*
X309257Y-143430D01*
X311877Y-142846D01*
X313406Y-141680D01*
X314061Y-139638D01*
X313624Y-137596D01*
X312532Y-136138D01*
X311004Y-135263D01*
X309476D01*
X307947Y-135846D01*
X306637Y-137305D01*
G01X298526Y-152763D02*
Y-135263D01*
X292849Y-149846D01*
X287172Y-135263D01*
Y-152763D01*
G01X280152D02*
Y-135263D01*
X275786D01*
X274039Y-136138D01*
X272729Y-137305D01*
X271637Y-139054D01*
X270764Y-141097D01*
X270546Y-144013D01*
X270764Y-146930D01*
X271637Y-148972D01*
X272729Y-150722D01*
X274039Y-151888D01*
X275786Y-152763D01*
X280152D01*
G01X253482Y-90263D02*
Y-107763D01*
X262216D01*
G01X279279D02*
Y-96097D01*
G01Y-98138D02*
X278406Y-96972D01*
X277095Y-96388D01*
X275567Y-96097D01*
X274039Y-96680D01*
X272729Y-97846D01*
X271855Y-99596D01*
X271419Y-101930D01*
X271855Y-104263D01*
X272729Y-106013D01*
X274039Y-107180D01*
X275567Y-107763D01*
X277095Y-107471D01*
X278406Y-106597D01*
X279279Y-105430D01*
G01X288264Y-113013D02*
X289574Y-113596D01*
X291321Y-113013D01*
X292412Y-111847D01*
X293286Y-110388D01*
X294595Y-105722D01*
X297434Y-96097D01*
G01X290447D02*
X294595Y-105722D01*
G01X307074Y-99888D02*
X314061D01*
X313406Y-97846D01*
X312314Y-96680D01*
X310786Y-96097D01*
X309257Y-96388D01*
X307947Y-97263D01*
X307074Y-99305D01*
X306637Y-101055D01*
Y-102805D01*
X307074Y-104555D01*
X308166Y-106305D01*
X309476Y-107471D01*
X311004Y-107763D01*
X312532Y-107180D01*
X314061Y-105430D01*
G01X324792Y-107763D02*
Y-96097D01*
G01Y-98430D02*
X325884Y-97263D01*
X326976Y-96388D01*
X328504Y-96097D01*
X329595Y-96388D01*
X330906Y-97263D01*
G01X342074Y-105722D02*
X343166Y-106888D01*
X344694Y-107763D01*
X346004D01*
X347314Y-107180D01*
X348187Y-106305D01*
X348624Y-105139D01*
X348406Y-103388D01*
X347532Y-102513D01*
X343602Y-100763D01*
X342729Y-98721D01*
X343166Y-97263D01*
X344039Y-96388D01*
X345349Y-96097D01*
X346659Y-96388D01*
X347969Y-97263D01*
G01X253150Y31496D02*
X344488D01*
G01X253150Y39370D02*
G03Y31496I0J-3937D01*
G01D02*
X344488D01*
G01X253150Y39370D02*
G03Y31496I0J-3937D01*
G01Y1937008D02*
X344496D01*
G01X253150D02*
G03Y1929134I0J-3937D01*
G01Y1937008D02*
X344496D01*
G01X253150D02*
G03Y1929134I0J-3937D01*
G01X356299Y0D02*
X417323D01*
G01X352362Y3937D02*
G03X356299Y0I3937J0D01*
G01X352362Y35433D02*
Y3937D01*
G01Y35433D02*
G03X348425Y39370I-3937J0D01*
G01X340551Y0D02*
G03X344488Y3937I0J3937D01*
G01Y7874D02*
Y3937D01*
G01X352362Y7874D02*
G03X344488I-3937J0D01*
G01Y31496D02*
G03X352362I3937J0D01*
G01X356299Y0D02*
X417323D01*
G01X352362Y3937D02*
G03X356299Y0I3937J0D01*
G01X352362Y35433D02*
Y3937D01*
G01Y35433D02*
G03X348425Y39370I-3937J0D01*
G01X340551Y0D02*
G03X344488Y3937I0J3937D01*
G01Y7874D02*
Y3937D01*
G01X352362Y7874D02*
G03X344488I-3937J0D01*
G01Y31496D02*
G03X352362I3937J0D01*
G01X348425Y1929134D02*
G03X352362Y1933071I0J3937D01*
G01Y1964567D02*
Y1933071D01*
G01X356299Y1968504D02*
G03X352362Y1964567I0J-3937D01*
G01X417323Y1968504D02*
X356299D01*
G01X344496Y1964567D02*
G03X340559Y1968504I-3937J0D01*
G01X344496Y1960889D02*
Y1964567D01*
G01Y1960889D02*
G03X352370I3937J0D01*
G01Y1937008D02*
G03X344496I-3937J0D01*
G01X348425Y1929134D02*
G03X352362Y1933071I0J3937D01*
G01Y1964567D02*
Y1933071D01*
G01X356299Y1968504D02*
G03X352362Y1964567I0J-3937D01*
G01X417323Y1968504D02*
X356299D01*
G01X344496Y1964567D02*
G03X340559Y1968504I-3937J0D01*
G01X344496Y1960889D02*
Y1964567D01*
G01Y1960889D02*
G03X352370I3937J0D01*
G01Y1937008D02*
G03X344496I-3937J0D01*
G01X404346Y-107763D02*
Y-90263D01*
X408712D01*
X410459Y-91138D01*
X411769Y-92305D01*
X412861Y-94054D01*
X413734Y-96097D01*
X413952Y-99013D01*
X413734Y-101930D01*
X412861Y-103972D01*
X411769Y-105722D01*
X410459Y-106888D01*
X408712Y-107763D01*
X404346D01*
G01X423374Y-99888D02*
X430361D01*
X429706Y-97846D01*
X428614Y-96680D01*
X427086Y-96097D01*
X425557Y-96388D01*
X424247Y-97263D01*
X423374Y-99305D01*
X422937Y-101055D01*
Y-102805D01*
X423374Y-104555D01*
X424466Y-106305D01*
X425776Y-107471D01*
X427304Y-107763D01*
X428832Y-107180D01*
X430361Y-105430D01*
G01X440874Y-105722D02*
X441966Y-106888D01*
X443494Y-107763D01*
X444804D01*
X446114Y-107180D01*
X446987Y-106305D01*
X447424Y-105139D01*
X447206Y-103388D01*
X446332Y-102513D01*
X442402Y-100763D01*
X441529Y-98721D01*
X441966Y-97263D01*
X442839Y-96388D01*
X444149Y-96097D01*
X445459Y-96388D01*
X446769Y-97263D01*
G01X461649Y-96097D02*
Y-107763D01*
G01Y-91430D02*
X461212Y-91138D01*
Y-90555D01*
X461649Y-90263D01*
X462086Y-90555D01*
Y-91138D01*
X461649Y-91430D01*
G01X476092Y-112138D02*
X477621Y-113305D01*
X479367Y-113596D01*
X480895Y-113305D01*
X482206Y-111847D01*
X483079Y-109805D01*
Y-96097D01*
G01Y-98430D02*
X482206Y-97263D01*
X480895Y-96388D01*
X479367Y-96097D01*
X477621Y-96680D01*
X476529Y-97846D01*
X475655Y-99888D01*
X475219Y-101930D01*
X475437Y-103680D01*
X476311Y-105722D01*
X477621Y-107180D01*
X479367Y-107763D01*
X480677Y-107471D01*
X482206Y-106305D01*
X483079Y-105139D01*
G01X492937Y-107763D02*
Y-96097D01*
G01Y-99013D02*
X493811Y-97555D01*
X495121Y-96388D01*
X496867Y-96097D01*
X498395Y-96388D01*
X499706Y-97555D01*
X500361Y-99596D01*
Y-107763D01*
G01X510874Y-99888D02*
X517861D01*
X517206Y-97846D01*
X516114Y-96680D01*
X514586Y-96097D01*
X513057Y-96388D01*
X511747Y-97263D01*
X510874Y-99305D01*
X510437Y-101055D01*
Y-102805D01*
X510874Y-104555D01*
X511966Y-106305D01*
X513276Y-107471D01*
X514804Y-107763D01*
X516332Y-107180D01*
X517861Y-105430D01*
G01X528592Y-107763D02*
Y-96097D01*
G01Y-98430D02*
X529684Y-97263D01*
X530776Y-96388D01*
X532304Y-96097D01*
X533395Y-96388D01*
X534706Y-97263D01*
G01X429134Y3937D02*
G03X433071Y0I3937J0D01*
G01X429134Y1964567D02*
Y3937D01*
G01X433071Y0D02*
X494095D01*
G01X421260Y3937D02*
Y1964567D01*
G01X417323Y0D02*
G03X421260Y3937I0J3937D01*
G01X429134Y11811D02*
G03X421260I-3937J0D01*
G01X429134Y3937D02*
G03X433071Y0I3937J0D01*
G01X429134Y1964567D02*
Y3937D01*
G01X433071Y0D02*
X494095D01*
G01X421260Y3937D02*
Y1964567D01*
G01X417323Y0D02*
G03X421260Y3937I0J3937D01*
G01X429134Y11811D02*
G03X421260I-3937J0D01*
G01Y42520D02*
G03X429134I3937J0D01*
G01X421260D02*
G03X429134I3937J0D01*
G01Y278740D02*
G03X421260I-3937J0D01*
G01X429134D02*
G03X421260I-3937J0D01*
G01Y309449D02*
G03X429134I3937J0D01*
G01X421260D02*
G03X429134I3937J0D01*
G01Y545669D02*
G03X421260I-3937J0D01*
G01X429134D02*
G03X421260I-3937J0D01*
G01Y576378D02*
G03X429134I3937J0D01*
G01X421260D02*
G03X429134I3937J0D01*
G01Y831496D02*
G03X421260I-3937J0D01*
G01X429134D02*
G03X421260I-3937J0D01*
G01Y862205D02*
G03X429134I3937J0D01*
G01X421260D02*
G03X429134I3937J0D01*
G01Y1106299D02*
G03X421260I-3937J0D01*
G01X429134D02*
G03X421260I-3937J0D01*
G01Y1137008D02*
G03X429134I3937J0D01*
G01X421260D02*
G03X429134I3937J0D01*
G01Y1392126D02*
G03X421260I-3937J0D01*
G01X429134D02*
G03X421260I-3937J0D01*
G01Y1422835D02*
G03X429134I3937J0D01*
G01X421260D02*
G03X429134I3937J0D01*
G01Y1659055D02*
G03X421260I-3937J0D01*
G01X429134D02*
G03X421260I-3937J0D01*
G01Y1689764D02*
G03X429134I3937J0D01*
G01X421260D02*
G03X429134I3937J0D01*
G01Y1925984D02*
G03X421260I-3937J0D01*
G01X429134D02*
G03X421260I-3937J0D01*
G01X433071Y1968504D02*
G03X429134Y1964567I0J-3937D01*
G01X494095Y1968504D02*
X433071D01*
G01X421260Y1964567D02*
G03X417323Y1968504I-3937J0D01*
G01X421260Y1956693D02*
G03X429134I3937J0D01*
G01X433071Y1968504D02*
G03X429134Y1964567I0J-3937D01*
G01X494095Y1968504D02*
X433071D01*
G01X421260Y1964567D02*
G03X417323Y1968504I-3937J0D01*
G01X421260Y1956693D02*
G03X429134I3937J0D01*
G01X433071Y1968504D02*
G03X429134Y1964567I0J-3937D01*
G01X421260D02*
G03X417323Y1968504I-3937J0D01*
G01X448096Y-152763D02*
Y-135263D01*
X452462D01*
X454209Y-136138D01*
X455519Y-137305D01*
X456611Y-139054D01*
X457484Y-141097D01*
X457702Y-144013D01*
X457484Y-146930D01*
X456611Y-148972D01*
X455519Y-150722D01*
X454209Y-151888D01*
X452462Y-152763D01*
X448096D01*
G01X470399Y-141097D02*
Y-152763D01*
G01Y-136430D02*
X469962Y-136138D01*
Y-135555D01*
X470399Y-135263D01*
X470836Y-135555D01*
Y-136138D01*
X470399Y-136430D01*
G01X487899Y-152763D02*
X486589Y-152471D01*
X485279Y-151305D01*
X484405Y-149263D01*
X483969Y-146930D01*
X484405Y-144596D01*
X485279Y-142555D01*
X486589Y-141388D01*
X487899Y-141097D01*
X489209Y-141388D01*
X490519Y-142555D01*
X491392Y-144596D01*
X491611Y-146930D01*
X491392Y-149263D01*
X490519Y-151305D01*
X489209Y-152471D01*
X487899Y-152763D01*
G01X501969Y39370D02*
G03X498032Y35433I0J-3937D01*
G01Y3937D02*
Y35433D01*
G01X494095Y0D02*
G03X498032Y3937I0J3937D01*
G01X505897Y0D02*
X648386D01*
G01X505897Y7615D02*
Y0D01*
G01X597244Y31496D02*
X505897D01*
G01Y7615D02*
G03X498023I-3937J0D01*
G01Y31496D02*
G03X505897I3937J0D01*
G01X501969Y39370D02*
G03X498032Y35433I0J-3937D01*
G01Y3937D02*
Y35433D01*
G01X494095Y0D02*
G03X498032Y3937I0J3937D01*
G01X505897Y0D02*
X620827D01*
G01X505897Y7615D02*
Y0D01*
G01X597244Y31496D02*
X505897D01*
G01Y7615D02*
G03X498023I-3937J0D01*
G01Y31496D02*
G03X505897I3937J0D01*
G01X501969Y39370D02*
X631890D01*
G01X501969D02*
X631890D01*
G01X498032Y1964567D02*
G03X494095Y1968504I-3937J0D01*
G01X498032Y1933071D02*
Y1960630D01*
G01Y1933071D02*
G03X501969Y1929134I3937J0D01*
G01X631890D02*
X501969D01*
G01X505906Y1960630D02*
Y1968504D01*
G01D02*
X648386D01*
G01X597244Y1937008D02*
X505906D01*
G01X498032Y1960630D02*
G03X505906I3937J0D01*
G01Y1937008D02*
G03X498032I-3937J0D01*
G01Y1964567D02*
G03X494095Y1968504I-3937J0D01*
G01X498032Y1933071D02*
Y1964567D01*
G01Y1933071D02*
G03X501969Y1929134I3937J0D01*
G01X631890D02*
X501969D01*
G01X505906Y1960630D02*
Y1968504D01*
G01D02*
X620827D01*
G01X597244Y1937008D02*
X505906D01*
G01X498032Y1960630D02*
G03X505906I3937J0D01*
G01Y1937008D02*
G03X498032I-3937J0D01*
G01X575349Y-152763D02*
Y-135263D01*
X572729Y-138763D01*
G01Y-152763D02*
X577969D01*
G01X588701Y-138180D02*
X590011Y-136430D01*
X591539Y-135555D01*
X593286Y-135263D01*
X595469Y-135846D01*
X596997Y-137305D01*
X597434Y-139054D01*
X597216Y-140805D01*
X596342Y-142263D01*
X591976Y-145180D01*
X590011Y-147221D01*
X588701Y-150139D01*
X588264Y-152763D01*
X597434D01*
G01X606419Y-153346D02*
X614279Y-135263D01*
G01X627849D02*
X626102Y-135846D01*
X624792Y-137305D01*
X623919Y-139054D01*
X623264Y-141388D01*
X623046Y-144013D01*
X623264Y-146638D01*
X623919Y-148972D01*
X624792Y-150722D01*
X626102Y-152180D01*
X627849Y-152763D01*
X629595Y-152180D01*
X630906Y-150722D01*
X631779Y-148972D01*
X632434Y-146638D01*
X632652Y-144013D01*
X632434Y-141388D01*
X631779Y-139054D01*
X630906Y-137305D01*
X629595Y-135846D01*
X627849Y-135263D01*
G01X644912Y-152763D02*
X645349Y-148972D01*
X646004Y-145763D01*
X646877Y-142846D01*
X647969Y-139638D01*
X649716Y-135263D01*
X640982D01*
G01X658919Y-153346D02*
X666779Y-135263D01*
G01X676201Y-138180D02*
X677511Y-136430D01*
X679039Y-135555D01*
X680786Y-135263D01*
X682969Y-135846D01*
X684497Y-137305D01*
X684934Y-139054D01*
X684716Y-140805D01*
X683842Y-142263D01*
X679476Y-145180D01*
X677511Y-147221D01*
X676201Y-150139D01*
X675764Y-152763D01*
X684934D01*
G01X697849Y-135263D02*
X696102Y-135846D01*
X694792Y-137305D01*
X693919Y-139054D01*
X693264Y-141388D01*
X693046Y-144013D01*
X693264Y-146638D01*
X693919Y-148972D01*
X694792Y-150722D01*
X696102Y-152180D01*
X697849Y-152763D01*
X699595Y-152180D01*
X700906Y-150722D01*
X701779Y-148972D01*
X702434Y-146638D01*
X702652Y-144013D01*
X702434Y-141388D01*
X701779Y-139054D01*
X700906Y-137305D01*
X699595Y-135846D01*
X697849Y-135263D01*
G01X715349Y-152763D02*
Y-135263D01*
X712729Y-138763D01*
G01Y-152763D02*
X717969D01*
G01X728701Y-138180D02*
X730011Y-136430D01*
X731539Y-135555D01*
X733286Y-135263D01*
X735469Y-135846D01*
X736997Y-137305D01*
X737434Y-139054D01*
X737216Y-140805D01*
X736342Y-142263D01*
X731976Y-145180D01*
X730011Y-147221D01*
X728701Y-150139D01*
X728264Y-152763D01*
X737434D01*
G01X623046Y-107763D02*
Y-90263D01*
X627412D01*
X629159Y-91138D01*
X630469Y-92305D01*
X631561Y-94054D01*
X632434Y-96097D01*
X632652Y-99013D01*
X632434Y-101930D01*
X631561Y-103972D01*
X630469Y-105722D01*
X629159Y-106888D01*
X627412Y-107763D01*
X623046D01*
G01X649279D02*
Y-96097D01*
G01Y-98138D02*
X648406Y-96972D01*
X647095Y-96388D01*
X645567Y-96097D01*
X644039Y-96680D01*
X642729Y-97846D01*
X641855Y-99596D01*
X641419Y-101930D01*
X641855Y-104263D01*
X642729Y-106013D01*
X644039Y-107180D01*
X645567Y-107763D01*
X647095Y-107471D01*
X648406Y-106597D01*
X649279Y-105430D01*
G01X662849Y-90263D02*
Y-107763D01*
G01X659792Y-96097D02*
X665906D01*
G01X677074Y-99888D02*
X684061D01*
X683406Y-97846D01*
X682314Y-96680D01*
X680786Y-96097D01*
X679257Y-96388D01*
X677947Y-97263D01*
X677074Y-99305D01*
X676637Y-101055D01*
Y-102805D01*
X677074Y-104555D01*
X678166Y-106305D01*
X679476Y-107471D01*
X681004Y-107763D01*
X682532Y-107180D01*
X684061Y-105430D01*
G01X635827Y31496D02*
G03X643701Y39370I0J7874D01*
G01X650689Y19685D02*
G03I-6988J0D01*
G01X635827Y31496D02*
X627953D01*
G01X597244D02*
G03Y39370I0J3937D01*
G01X627953D02*
G03Y31496I0J-3937D01*
G01X650689Y19685D02*
G03I-6988J0D01*
G01X635827Y31496D02*
X627953D01*
G01X597244D02*
G03Y39370I0J3937D01*
G01X627953D02*
G03Y31496I0J-3937D01*
G01X635827Y161417D02*
Y43307D01*
G01X631890Y39370D02*
G03X635827Y43307I0J3937D01*
G01X631890Y39370D02*
G03X635827Y43307I0J3937D01*
G01X643701Y169256D02*
G03X635827I-3937J0D01*
G01X643701D02*
G03X635827I-3937J0D01*
G01Y161417D02*
Y1807087D01*
G01Y161417D02*
Y1807087D01*
G01Y199965D02*
G03X643701I3937J0D01*
G01X635827D02*
G03X643701I3937J0D01*
G01Y436186D02*
G03X635827I-3937J0D01*
G01X643701D02*
G03X635827I-3937J0D01*
G01Y466894D02*
G03X643701I3937J0D01*
G01X635827D02*
G03X643701I3937J0D01*
G01Y703115D02*
G03X635827I-3937J0D01*
G01Y733823D02*
G03X643701I3937J0D01*
G01Y703115D02*
G03X635827I-3937J0D01*
G01Y733823D02*
G03X643701I3937J0D01*
G01X635827Y997603D02*
G03X643701I3937J0D01*
G01Y970832D02*
G03X635827I-3937J0D01*
G01Y997603D02*
G03X643701I3937J0D01*
G01Y970832D02*
G03X635827I-3937J0D01*
G01Y1265320D02*
G03X643701I3937J0D01*
G01Y1234611D02*
G03X635827I-3937J0D01*
G01Y1265320D02*
G03X643701I3937J0D01*
G01Y1234611D02*
G03X635827I-3937J0D01*
G01X643701Y1501541D02*
G03X635827I-3937J0D01*
G01X643701D02*
G03X635827I-3937J0D01*
G01Y1532249D02*
G03X643701I3937J0D01*
G01X635827D02*
G03X643701I3937J0D01*
G01Y1768470D02*
G03X635827I-3937J0D01*
G01X643701D02*
G03X635827I-3937J0D01*
G01Y1799178D02*
G03X643701I3937J0D01*
G01X635827D02*
G03X643701I3937J0D01*
G01X635827Y1818898D02*
Y1807087D01*
G01Y1818898D02*
Y1925197D01*
G01Y1818898D02*
Y1925197D01*
G01D02*
G03X631890Y1929134I-3937J0D01*
G01X635827Y1925197D02*
G03X631890Y1929134I-3937J0D01*
G01X643701D02*
G03X635827Y1937008I-7874J0D01*
G01X650689Y1948819D02*
G03I-6988J0D01*
G01X627953Y1937008D02*
X635827D01*
G01X627953D02*
G03Y1929134I0J-3937D01*
G01X597244D02*
G03Y1937008I0J3937D01*
G01X650689Y1948819D02*
G03I-6988J0D01*
G01X627953Y1937008D02*
X635827D01*
G01X627953D02*
G03Y1929134I0J-3937D01*
G01X597244D02*
G03Y1937008I0J3937D01*
G01X650689Y1948819D02*
G03I-6988J0D01*
G01X648386Y0D02*
G03X663386Y15000I0J15000D01*
G01Y1953504D02*
Y15000D01*
G01X643701Y169256D02*
Y39370D01*
G01Y436186D02*
Y199965D01*
G01Y703115D02*
Y466894D01*
G01Y970832D02*
Y733823D01*
G01Y1234611D02*
Y997603D01*
G01Y1501541D02*
Y1265320D01*
G01Y1768470D02*
Y1532249D01*
G01Y1929134D02*
Y1799178D01*
G01X663386Y1953504D02*
G03X648386Y1968504I-15000J0D01*
M02*
